(kicad_pcb
	(version 20260206)
	(generator "pcbnew")
	(generator_version "10.0")
	(general
		(thickness 1.6)
		(legacy_teardrops no)
	)
	(paper "A4")
	(title_block
		(title "Wiwynn_Tioga_Pass_MB.brd")
		(comment 1 "Tioga Pass / footprint 431 of 4770 (J4A1), pads 1-123 of 291")
	)
	(layers
		(0 "F.Cu" signal "TOP")
		(4 "In1.Cu" signal "L2GND")
		(6 "In2.Cu" signal "L3")
		(8 "In3.Cu" signal "L4GND")
		(10 "In4.Cu" signal "L5")
		(12 "In5.Cu" signal "L6GND")
		(14 "In6.Cu" signal "L7VCC")
		(16 "In7.Cu" signal "L8VCC")
		(18 "In8.Cu" signal "L9GND")
		(20 "In9.Cu" signal "L10")
		(22 "In10.Cu" signal "L11GND")
		(24 "In11.Cu" signal "L12")
		(26 "In12.Cu" signal "L13GND")
		(2 "B.Cu" signal "BOTTOM")
		(9 "F.Adhes" user "F.Adhesive")
		(11 "B.Adhes" user "B.Adhesive")
		(13 "F.Paste" user "Package Geometry/Pastemask Top")
		(15 "B.Paste" user "Package Geometry/Pastemask Bottom")
		(5 "F.SilkS" user "Ref Des/Silkscreen Top")
		(7 "B.SilkS" user "Ref Des/Silkscreen Bottom")
		(1 "F.Mask" user "Board Geometry/Soldermask Top")
		(3 "B.Mask" user "Board Geometry/Soldermask Bottom")
		(17 "Dwgs.User" user "User.Drawings")
		(19 "Cmts.User" user "User.Comments")
		(21 "Eco1.User" user "User.Eco1")
		(23 "Eco2.User" user "User.Eco2")
		(25 "Edge.Cuts" user "Board Geometry/Outline")
		(27 "Margin" user)
		(31 "F.CrtYd" user "Package Geometry/Place Bound Top")
		(29 "B.CrtYd" user "Package Geometry/Place Bound Bottom")
		(35 "F.Fab" user "Ref Des/Assembly Top")
		(33 "B.Fab" user "Ref Des/Assembly Bottom")
	)
	(footprint ""
		(layer "F.Cu")
		(at 194.700398 -152.273 90)
		(property "Reference" "J4A1"
			(at -2.699512 42.53611 0)
			(unlocked yes)
			(layer "F.SilkS")
			(effects
				(font
					(size 0.7874 0.5842)
					(thickness 0.1524)
				)
				(justify left)
			)
		)
		(property "Value" ""
			(at 0 0 90)
			(layer "F.Fab")
			(effects
				(font
					(size 1.27 1.27)
				)
			)
		)
		(duplicate_pad_numbers_are_jumpers no)
		(pad "" thru_hole circle
			(at 2.29997 -5.649976 90)
			(size 2.8194 2.8194)
			(drill 2.4384)
			(layers "*.Cu" "*.Mask")
			(remove_unused_layers no)
			(clearance 0.127)
			(thermal_gap 0.127)
		)
		(pad "" thru_hole oval
			(at 2.29997 68.90004 90)
			(size 2.8194 1.5748)
			(drill oval 2.4384 1.1938)
			(layers "*.Cu" "*.Mask")
			(remove_unused_layers no)
			(clearance 0.127)
			(thermal_gap 0.127)
		)
		(pad "" thru_hole circle
			(at 2.29997 132.299964 90)
			(size 2.8194 2.8194)
			(drill 2.4384)
			(layers "*.Cu" "*.Mask")
			(remove_unused_layers no)
			(clearance 0.127)
			(thermal_gap 0.127)
		)
		(pad "1" smd rect
			(at 0 0 90)
			(size 1.8034 0.508)
			(layers "F.Cu" "F.Mask" "F.Paste")
			(net "P12V_NVDIMM_DEF")
		)
		(pad "2" smd rect
			(at 0 0.849884 90)
			(size 1.8034 0.508)
			(layers "F.Cu" "F.Mask" "F.Paste")
			(net "GND")
		)
		(pad "3" smd rect
			(at 0 1.700022 90)
			(size 1.8034 0.508)
			(layers "F.Cu" "F.Mask" "F.Paste")
			(net "M_F_DQ<5>")
		)
		(pad "4" smd rect
			(at 0 2.549906 90)
			(size 1.8034 0.508)
			(layers "F.Cu" "F.Mask" "F.Paste")
			(net "GND")
		)
		(pad "5" smd rect
			(at 0 3.400044 90)
			(size 1.8034 0.508)
			(layers "F.Cu" "F.Mask" "F.Paste")
			(net "M_F_DQ<1>")
		)
		(pad "6" smd rect
			(at 0 4.249928 90)
			(size 1.8034 0.508)
			(layers "F.Cu" "F.Mask" "F.Paste")
			(net "GND")
		)
		(pad "7" smd rect
			(at 0 5.100066 90)
			(size 1.8034 0.508)
			(layers "F.Cu" "F.Mask" "F.Paste")
			(net "M_F_DQS_DP<9>")
		)
		(pad "8" smd rect
			(at 0 5.94995 90)
			(size 1.8034 0.508)
			(layers "F.Cu" "F.Mask" "F.Paste")
			(net "M_F_DQS_DN<9>")
		)
		(pad "9" smd rect
			(at 0 6.800088 90)
			(size 1.8034 0.508)
			(layers "F.Cu" "F.Mask" "F.Paste")
			(net "GND")
		)
		(pad "10" smd rect
			(at 0 7.649972 90)
			(size 1.8034 0.508)
			(layers "F.Cu" "F.Mask" "F.Paste")
			(net "M_F_DQ<7>")
		)
		(pad "11" smd rect
			(at 0 8.50011 90)
			(size 1.8034 0.508)
			(layers "F.Cu" "F.Mask" "F.Paste")
			(net "GND")
		)
		(pad "12" smd rect
			(at 0 9.349994 90)
			(size 1.8034 0.508)
			(layers "F.Cu" "F.Mask" "F.Paste")
			(net "M_F_DQ<3>")
		)
		(pad "13" smd rect
			(at 0 10.199878 90)
			(size 1.8034 0.508)
			(layers "F.Cu" "F.Mask" "F.Paste")
			(net "GND")
		)
		(pad "14" smd rect
			(at 0 11.050016 90)
			(size 1.8034 0.508)
			(layers "F.Cu" "F.Mask" "F.Paste")
			(net "M_F_DQ<13>")
		)
		(pad "15" smd rect
			(at 0 11.8999 90)
			(size 1.8034 0.508)
			(layers "F.Cu" "F.Mask" "F.Paste")
			(net "GND")
		)
		(pad "16" smd rect
			(at 0 12.750038 90)
			(size 1.8034 0.508)
			(layers "F.Cu" "F.Mask" "F.Paste")
			(net "M_F_DQ<9>")
		)
		(pad "17" smd rect
			(at 0 13.599922 90)
			(size 1.8034 0.508)
			(layers "F.Cu" "F.Mask" "F.Paste")
			(net "GND")
		)
		(pad "18" smd rect
			(at 0 14.45006 90)
			(size 1.8034 0.508)
			(layers "F.Cu" "F.Mask" "F.Paste")
			(net "M_F_DQS_DP<10>")
		)
		(pad "19" smd rect
			(at 0 15.299944 90)
			(size 1.8034 0.508)
			(layers "F.Cu" "F.Mask" "F.Paste")
			(net "M_F_DQS_DN<10>")
		)
		(pad "20" smd rect
			(at 0 16.150082 90)
			(size 1.8034 0.508)
			(layers "F.Cu" "F.Mask" "F.Paste")
			(net "GND")
		)
		(pad "21" smd rect
			(at 0 16.999966 90)
			(size 1.8034 0.508)
			(layers "F.Cu" "F.Mask" "F.Paste")
			(net "M_F_DQ<15>")
		)
		(pad "22" smd rect
			(at 0 17.850104 90)
			(size 1.8034 0.508)
			(layers "F.Cu" "F.Mask" "F.Paste")
			(net "GND")
		)
		(pad "23" smd rect
			(at 0 18.699988 90)
			(size 1.8034 0.508)
			(layers "F.Cu" "F.Mask" "F.Paste")
			(net "M_F_DQ<11>")
		)
		(pad "24" smd rect
			(at 0 19.550126 90)
			(size 1.8034 0.508)
			(layers "F.Cu" "F.Mask" "F.Paste")
			(net "GND")
		)
		(pad "25" smd rect
			(at 0 20.40001 90)
			(size 1.8034 0.508)
			(layers "F.Cu" "F.Mask" "F.Paste")
			(net "M_F_DQ<21>")
		)
		(pad "26" smd rect
			(at 0 21.249894 90)
			(size 1.8034 0.508)
			(layers "F.Cu" "F.Mask" "F.Paste")
			(net "GND")
		)
		(pad "27" smd rect
			(at 0 22.100032 90)
			(size 1.8034 0.508)
			(layers "F.Cu" "F.Mask" "F.Paste")
			(net "M_F_DQ<17>")
		)
		(pad "28" smd rect
			(at 0 22.949916 90)
			(size 1.8034 0.508)
			(layers "F.Cu" "F.Mask" "F.Paste")
			(net "GND")
		)
		(pad "29" smd rect
			(at 0 23.800054 90)
			(size 1.8034 0.508)
			(layers "F.Cu" "F.Mask" "F.Paste")
			(net "M_F_DQS_DP<11>")
		)
		(pad "30" smd rect
			(at 0 24.649938 90)
			(size 1.8034 0.508)
			(layers "F.Cu" "F.Mask" "F.Paste")
			(net "M_F_DQS_DN<11>")
		)
		(pad "31" smd rect
			(at 0 25.500076 90)
			(size 1.8034 0.508)
			(layers "F.Cu" "F.Mask" "F.Paste")
			(net "GND")
		)
		(pad "32" smd rect
			(at 0 26.34996 90)
			(size 1.8034 0.508)
			(layers "F.Cu" "F.Mask" "F.Paste")
			(net "M_F_DQ<23>")
		)
		(pad "33" smd rect
			(at 0 27.200098 90)
			(size 1.8034 0.508)
			(layers "F.Cu" "F.Mask" "F.Paste")
			(net "GND")
		)
		(pad "34" smd rect
			(at 0 28.049982 90)
			(size 1.8034 0.508)
			(layers "F.Cu" "F.Mask" "F.Paste")
			(net "M_F_DQ<19>")
		)
		(pad "35" smd rect
			(at 0 28.90012 90)
			(size 1.8034 0.508)
			(layers "F.Cu" "F.Mask" "F.Paste")
			(net "GND")
		)
		(pad "36" smd rect
			(at 0 29.750004 90)
			(size 1.8034 0.508)
			(layers "F.Cu" "F.Mask" "F.Paste")
			(net "M_F_DQ<29>")
		)
		(pad "37" smd rect
			(at 0 30.599888 90)
			(size 1.8034 0.508)
			(layers "F.Cu" "F.Mask" "F.Paste")
			(net "GND")
		)
		(pad "38" smd rect
			(at 0 31.450026 90)
			(size 1.8034 0.508)
			(layers "F.Cu" "F.Mask" "F.Paste")
			(net "M_F_DQ<25>")
		)
		(pad "39" smd rect
			(at 0 32.29991 90)
			(size 1.8034 0.508)
			(layers "F.Cu" "F.Mask" "F.Paste")
			(net "GND")
		)
		(pad "40" smd rect
			(at 0 33.150048 90)
			(size 1.8034 0.508)
			(layers "F.Cu" "F.Mask" "F.Paste")
			(net "M_F_DQS_DP<12>")
		)
		(pad "41" smd rect
			(at 0 33.999932 90)
			(size 1.8034 0.508)
			(layers "F.Cu" "F.Mask" "F.Paste")
			(net "M_F_DQS_DN<12>")
		)
		(pad "42" smd rect
			(at 0 34.85007 90)
			(size 1.8034 0.508)
			(layers "F.Cu" "F.Mask" "F.Paste")
			(net "GND")
		)
		(pad "43" smd rect
			(at 0 35.699954 90)
			(size 1.8034 0.508)
			(layers "F.Cu" "F.Mask" "F.Paste")
			(net "M_F_DQ<31>")
		)
		(pad "44" smd rect
			(at 0 36.550092 90)
			(size 1.8034 0.508)
			(layers "F.Cu" "F.Mask" "F.Paste")
			(net "GND")
		)
		(pad "45" smd rect
			(at 0 37.399976 90)
			(size 1.8034 0.508)
			(layers "F.Cu" "F.Mask" "F.Paste")
			(net "M_F_DQ<27>")
		)
		(pad "46" smd rect
			(at 0 38.250114 90)
			(size 1.8034 0.508)
			(layers "F.Cu" "F.Mask" "F.Paste")
			(net "GND")
		)
		(pad "47" smd rect
			(at 0 39.099998 90)
			(size 1.8034 0.508)
			(layers "F.Cu" "F.Mask" "F.Paste")
			(net "M_F_ECC<5>")
		)
		(pad "48" smd rect
			(at 0 39.949882 90)
			(size 1.8034 0.508)
			(layers "F.Cu" "F.Mask" "F.Paste")
			(net "GND")
		)
		(pad "49" smd rect
			(at 0 40.80002 90)
			(size 1.8034 0.508)
			(layers "F.Cu" "F.Mask" "F.Paste")
			(net "M_F_ECC<1>")
		)
		(pad "50" smd rect
			(at 0 41.649904 90)
			(size 1.8034 0.508)
			(layers "F.Cu" "F.Mask" "F.Paste")
			(net "GND")
		)
		(pad "51" smd rect
			(at 0 42.500042 90)
			(size 1.8034 0.508)
			(layers "F.Cu" "F.Mask" "F.Paste")
			(net "M_F_DQS_DP<17>")
		)
		(pad "52" smd rect
			(at 0 43.349926 90)
			(size 1.8034 0.508)
			(layers "F.Cu" "F.Mask" "F.Paste")
			(net "M_F_DQS_DN<17>")
		)
		(pad "53" smd rect
			(at 0 44.200064 90)
			(size 1.8034 0.508)
			(layers "F.Cu" "F.Mask" "F.Paste")
			(net "GND")
		)
		(pad "54" smd rect
			(at 0 45.049948 90)
			(size 1.8034 0.508)
			(layers "F.Cu" "F.Mask" "F.Paste")
			(net "M_F_ECC<7>")
		)
		(pad "55" smd rect
			(at 0 45.900086 90)
			(size 1.8034 0.508)
			(layers "F.Cu" "F.Mask" "F.Paste")
			(net "GND")
		)
		(pad "56" smd rect
			(at 0 46.74997 90)
			(size 1.8034 0.508)
			(layers "F.Cu" "F.Mask" "F.Paste")
			(net "M_F_ECC<3>")
		)
		(pad "57" smd rect
			(at 0 47.600108 90)
			(size 1.8034 0.508)
			(layers "F.Cu" "F.Mask" "F.Paste")
			(net "GND")
		)
		(pad "58" smd rect
			(at 0 48.449992 90)
			(size 1.8034 0.508)
			(layers "F.Cu" "F.Mask" "F.Paste")
			(net "M_DEF_RST_N")
		)
		(pad "59" smd rect
			(at 0 49.299876 90)
			(size 1.8034 0.508)
			(layers "F.Cu" "F.Mask" "F.Paste")
			(net "PVDDQ_DEF")
		)
		(pad "60" smd rect
			(at 0 50.150014 90)
			(size 1.8034 0.508)
			(layers "F.Cu" "F.Mask" "F.Paste")
			(net "M_F_CKE<0>")
		)
		(pad "61" smd rect
			(at 0 50.999898 90)
			(size 1.8034 0.508)
			(layers "F.Cu" "F.Mask" "F.Paste")
			(net "PVDDQ_DEF")
		)
		(pad "62" smd rect
			(at 0 51.850036 90)
			(size 1.8034 0.508)
			(layers "F.Cu" "F.Mask" "F.Paste")
			(net "M_F_ACT_N")
		)
		(pad "63" smd rect
			(at 0 52.69992 90)
			(size 1.8034 0.508)
			(layers "F.Cu" "F.Mask" "F.Paste")
			(net "M_F_BG<0>")
		)
		(pad "64" smd rect
			(at 0 53.550058 90)
			(size 1.8034 0.508)
			(layers "F.Cu" "F.Mask" "F.Paste")
			(net "PVDDQ_DEF")
		)
		(pad "65" smd rect
			(at 0 54.399942 90)
			(size 1.8034 0.508)
			(layers "F.Cu" "F.Mask" "F.Paste")
			(net "M_F_MA<12>")
		)
		(pad "66" smd rect
			(at 0 55.25008 90)
			(size 1.8034 0.508)
			(layers "F.Cu" "F.Mask" "F.Paste")
			(net "M_F_MA<9>")
		)
		(pad "67" smd rect
			(at 0 56.099964 90)
			(size 1.8034 0.508)
			(layers "F.Cu" "F.Mask" "F.Paste")
			(net "PVDDQ_DEF")
		)
		(pad "68" smd rect
			(at 0 56.950102 90)
			(size 1.8034 0.508)
			(layers "F.Cu" "F.Mask" "F.Paste")
			(net "M_F_MA<8>")
		)
		(pad "69" smd rect
			(at 0 57.799986 90)
			(size 1.8034 0.508)
			(layers "F.Cu" "F.Mask" "F.Paste")
			(net "M_F_MA<6>")
		)
		(pad "70" smd rect
			(at 0 58.650124 90)
			(size 1.8034 0.508)
			(layers "F.Cu" "F.Mask" "F.Paste")
			(net "PVDDQ_DEF")
		)
		(pad "71" smd rect
			(at 0 59.500008 90)
			(size 1.8034 0.508)
			(layers "F.Cu" "F.Mask" "F.Paste")
			(net "M_F_MA<3>")
		)
		(pad "72" smd rect
			(at 0 60.349892 90)
			(size 1.8034 0.508)
			(layers "F.Cu" "F.Mask" "F.Paste")
			(net "M_F_MA<1>")
		)
		(pad "73" smd rect
			(at 0 61.20003 90)
			(size 1.8034 0.508)
			(layers "F.Cu" "F.Mask" "F.Paste")
			(net "PVDDQ_DEF")
		)
		(pad "74" smd rect
			(at 0 62.049914 90)
			(size 1.8034 0.508)
			(layers "F.Cu" "F.Mask" "F.Paste")
			(net "M_F_CLK_DP<0>")
		)
		(pad "75" smd rect
			(at 0 62.900052 90)
			(size 1.8034 0.508)
			(layers "F.Cu" "F.Mask" "F.Paste")
			(net "M_F_CLK_DN<0>")
		)
		(pad "76" smd rect
			(at 0 63.749936 90)
			(size 1.8034 0.508)
			(layers "F.Cu" "F.Mask" "F.Paste")
			(net "PVDDQ_DEF")
		)
		(pad "77" smd rect
			(at 0 64.600074 90)
			(size 1.8034 0.508)
			(layers "F.Cu" "F.Mask" "F.Paste")
			(net "PVTT_DEF")
		)
		(pad "78" smd rect
			(at 0 70.550024 90)
			(size 1.8034 0.508)
			(layers "F.Cu" "F.Mask" "F.Paste")
			(net "FM_DIMM_EVENT_COD_N")
		)
		(pad "79" smd rect
			(at 0 71.399908 90)
			(size 1.8034 0.508)
			(layers "F.Cu" "F.Mask" "F.Paste")
			(net "M_F_MA<0>")
		)
		(pad "80" smd rect
			(at 0 72.250046 90)
			(size 1.8034 0.508)
			(layers "F.Cu" "F.Mask" "F.Paste")
			(net "PVDDQ_DEF")
		)
		(pad "81" smd rect
			(at 0 73.09993 90)
			(size 1.8034 0.508)
			(layers "F.Cu" "F.Mask" "F.Paste")
			(net "M_F_BA<0>")
		)
		(pad "82" smd rect
			(at 0 73.950068 90)
			(size 1.8034 0.508)
			(layers "F.Cu" "F.Mask" "F.Paste")
			(net "M_F_MA<16>")
		)
		(pad "83" smd rect
			(at 0 74.799952 90)
			(size 1.8034 0.508)
			(layers "F.Cu" "F.Mask" "F.Paste")
			(net "PVDDQ_DEF")
		)
		(pad "84" smd rect
			(at 0 75.65009 90)
			(size 1.8034 0.508)
			(layers "F.Cu" "F.Mask" "F.Paste")
			(net "M_F_CS_N<0>")
		)
		(pad "85" smd rect
			(at 0 76.499974 90)
			(size 1.8034 0.508)
			(layers "F.Cu" "F.Mask" "F.Paste")
			(net "PVDDQ_DEF")
		)
		(pad "86" smd rect
			(at 0 77.350112 90)
			(size 1.8034 0.508)
			(layers "F.Cu" "F.Mask" "F.Paste")
			(net "M_F_MA<15>")
		)
		(pad "87" smd rect
			(at 0 78.199996 90)
			(size 1.8034 0.508)
			(layers "F.Cu" "F.Mask" "F.Paste")
			(net "M_F_ODT<0>")
		)
		(pad "88" smd rect
			(at 0 79.04988 90)
			(size 1.8034 0.508)
			(layers "F.Cu" "F.Mask" "F.Paste")
			(net "PVDDQ_DEF")
		)
		(pad "89" smd rect
			(at 0 79.900018 90)
			(size 1.8034 0.508)
			(layers "F.Cu" "F.Mask" "F.Paste")
			(net "M_F_CS_N<1>")
		)
		(pad "90" smd rect
			(at 0 80.749902 90)
			(size 1.8034 0.508)
			(layers "F.Cu" "F.Mask" "F.Paste")
			(net "PVDDQ_DEF")
		)
		(pad "91" smd rect
			(at 0 81.60004 90)
			(size 1.8034 0.508)
			(layers "F.Cu" "F.Mask" "F.Paste")
			(net "M_F_ODT<1>")
		)
		(pad "92" smd rect
			(at 0 82.449924 90)
			(size 1.8034 0.508)
			(layers "F.Cu" "F.Mask" "F.Paste")
			(net "PVDDQ_DEF")
		)
		(pad "93" smd rect
			(at 0 83.300062 90)
			(size 1.8034 0.508)
			(layers "F.Cu" "F.Mask" "F.Paste")
			(net "M_F_CS_N<2>")
		)
		(pad "94" smd rect
			(at 0 84.149946 90)
			(size 1.8034 0.508)
			(layers "F.Cu" "F.Mask" "F.Paste")
			(net "GND")
		)
		(pad "95" smd rect
			(at 0 85.000084 90)
			(size 1.8034 0.508)
			(layers "F.Cu" "F.Mask" "F.Paste")
			(net "M_F_DQ<37>")
		)
		(pad "96" smd rect
			(at 0 85.849968 90)
			(size 1.8034 0.508)
			(layers "F.Cu" "F.Mask" "F.Paste")
			(net "GND")
		)
		(pad "97" smd rect
			(at 0 86.700106 90)
			(size 1.8034 0.508)
			(layers "F.Cu" "F.Mask" "F.Paste")
			(net "M_F_DQ<33>")
		)
		(pad "98" smd rect
			(at 0 87.54999 90)
			(size 1.8034 0.508)
			(layers "F.Cu" "F.Mask" "F.Paste")
			(net "GND")
		)
		(pad "99" smd rect
			(at 0 88.399874 90)
			(size 1.8034 0.508)
			(layers "F.Cu" "F.Mask" "F.Paste")
			(net "M_F_DQS_DP<13>")
		)
		(pad "100" smd rect
			(at 0 89.250012 90)
			(size 1.8034 0.508)
			(layers "F.Cu" "F.Mask" "F.Paste")
			(net "M_F_DQS_DN<13>")
		)
		(pad "101" smd rect
			(at 0 90.099896 90)
			(size 1.8034 0.508)
			(layers "F.Cu" "F.Mask" "F.Paste")
			(net "GND")
		)
		(pad "102" smd rect
			(at 0 90.950034 90)
			(size 1.8034 0.508)
			(layers "F.Cu" "F.Mask" "F.Paste")
			(net "M_F_DQ<39>")
		)
		(pad "103" smd rect
			(at 0 91.799918 90)
			(size 1.8034 0.508)
			(layers "F.Cu" "F.Mask" "F.Paste")
			(net "GND")
		)
		(pad "104" smd rect
			(at 0 92.650056 90)
			(size 1.8034 0.508)
			(layers "F.Cu" "F.Mask" "F.Paste")
			(net "M_F_DQ<35>")
		)
		(pad "105" smd rect
			(at 0 93.49994 90)
			(size 1.8034 0.508)
			(layers "F.Cu" "F.Mask" "F.Paste")
			(net "GND")
		)
		(pad "106" smd rect
			(at 0 94.350078 90)
			(size 1.8034 0.508)
			(layers "F.Cu" "F.Mask" "F.Paste")
			(net "M_F_DQ<45>")
		)
		(pad "107" smd rect
			(at 0 95.199962 90)
			(size 1.8034 0.508)
			(layers "F.Cu" "F.Mask" "F.Paste")
			(net "GND")
		)
		(pad "108" smd rect
			(at 0 96.0501 90)
			(size 1.8034 0.508)
			(layers "F.Cu" "F.Mask" "F.Paste")
			(net "M_F_DQ<41>")
		)
		(pad "109" smd rect
			(at 0 96.899984 90)
			(size 1.8034 0.508)
			(layers "F.Cu" "F.Mask" "F.Paste")
			(net "GND")
		)
		(pad "110" smd rect
			(at 0 97.750122 90)
			(size 1.8034 0.508)
			(layers "F.Cu" "F.Mask" "F.Paste")
			(net "M_F_DQS_DP<14>")
		)
		(pad "111" smd rect
			(at 0 98.600006 90)
			(size 1.8034 0.508)
			(layers "F.Cu" "F.Mask" "F.Paste")
			(net "M_F_DQS_DN<14>")
		)
		(pad "112" smd rect
			(at 0 99.44989 90)
			(size 1.8034 0.508)
			(layers "F.Cu" "F.Mask" "F.Paste")
			(net "GND")
		)
		(pad "113" smd rect
			(at 0 100.300028 90)
			(size 1.8034 0.508)
			(layers "F.Cu" "F.Mask" "F.Paste")
			(net "M_F_DQ<47>")
		)
		(pad "114" smd rect
			(at 0 101.149912 90)
			(size 1.8034 0.508)
			(layers "F.Cu" "F.Mask" "F.Paste")
			(net "GND")
		)
		(pad "115" smd rect
			(at 0 102.00005 90)
			(size 1.8034 0.508)
			(layers "F.Cu" "F.Mask" "F.Paste")
			(net "M_F_DQ<43>")
		)
		(pad "116" smd rect
			(at 0 102.849934 90)
			(size 1.8034 0.508)
			(layers "F.Cu" "F.Mask" "F.Paste")
			(net "GND")
		)
		(pad "117" smd rect
			(at 0 103.700072 90)
			(size 1.8034 0.508)
			(layers "F.Cu" "F.Mask" "F.Paste")
			(net "M_F_DQ<53>")
		)
		(pad "118" smd rect
			(at 0 104.549956 90)
			(size 1.8034 0.508)
			(layers "F.Cu" "F.Mask" "F.Paste")
			(net "GND")
		)
		(pad "119" smd rect
			(at 0 105.400094 90)
			(size 1.8034 0.508)
			(layers "F.Cu" "F.Mask" "F.Paste")
			(net "M_F_DQ<49>")
		)
		(pad "120" smd rect
			(at 0 106.249978 90)
			(size 1.8034 0.508)
			(layers "F.Cu" "F.Mask" "F.Paste")
			(net "GND")
		)
	)
)
